# T6G (Grand Teton) — schematic netlist excerpt (pin names and nets, part order shuffled) for the footprints in the layout excerpt that follows; sources: Cadence DE-HDL packaged netlist, KiCad conversion of 04192023_DAF0TMB3IC0_F0TG_MB_C_brd_V02_OCP.brd

R593  Q_RES  10K 1% CHIP  pkg 0402LF  page 183 : A = FM_9ZXL045_P1_1_OE_N ; B = GND
C553  Q_CAP  0.1UF 25V 10% X7R  pkg 0402  page 171 : A = P3V3_AUX ; B = GND

(kicad_pcb
	(version 20260206)
	(generator "pcbnew")
	(generator_version "10.0")
	(general
		(thickness 1.6)
		(legacy_teardrops no)
	)
	(paper "A4")
	(title_block
		(title "04192023_DAF0TMB3IC0_F0TG_MB_C_brd_V02_OCP.brd")
		(comment 1 "Grand Teton / footprints 952-953 of 8354")
	)
	(layers
		(0 "F.Cu" signal "TOP")
		(4 "In1.Cu" signal "GND")
		(6 "In2.Cu" signal "IN1")
		(8 "In3.Cu" signal "GND1")
		(10 "In4.Cu" signal "IN2")
		(12 "In5.Cu" signal "GND2")
		(14 "In6.Cu" signal "IN3")
		(16 "In7.Cu" signal "GND3")
		(18 "In8.Cu" signal "VCC")
		(20 "In9.Cu" signal "VCC1")
		(22 "In10.Cu" signal "GND4")
		(24 "In11.Cu" signal "IN4")
		(26 "In12.Cu" signal "GND5")
		(28 "In13.Cu" signal "IN5")
		(30 "In14.Cu" signal "GND6")
		(32 "In15.Cu" signal "IN6")
		(34 "In16.Cu" signal "GND7")
		(2 "B.Cu" signal "BOTTOM")
		(9 "F.Adhes" user "F.Adhesive")
		(11 "B.Adhes" user "B.Adhesive")
		(13 "F.Paste" user "Package Geometry/Pastemask Top")
		(15 "B.Paste" user "Package Geometry/Pastemask Bottom")
		(5 "F.SilkS" user "Ref Des/Silkscreen Top")
		(7 "B.SilkS" user "Ref Des/Silkscreen Bottom")
		(1 "F.Mask" user "Board Geometry/Soldermask Top")
		(3 "B.Mask" user "Board Geometry/Soldermask Bottom")
		(17 "Dwgs.User" user "User.Drawings")
		(19 "Cmts.User" user "User.Comments")
		(21 "Eco1.User" user "User.Eco1")
		(23 "Eco2.User" user "User.Eco2")
		(25 "Edge.Cuts" user "Board Geometry/Outline")
		(27 "Margin" user)
		(31 "F.CrtYd" user "Package Geometry/Place Bound Top")
		(29 "B.CrtYd" user "Package Geometry/Place Bound Bottom")
		(35 "F.Fab" user "Ref Des/Assembly Top")
		(33 "B.Fab" user "Ref Des/Assembly Bottom")
	)
	(footprint ""
		(layer "F.Cu")
		(at 100.48367 -406.151588 180)
		(property "Reference" "R593"
			(at 0 0 180)
			(layer "F.SilkS")
			(hide yes)
			(effects
				(font
					(size 1.27 1.27)
				)
			)
		)
		(property "Value" ""
			(at 0 0 180)
			(layer "F.Fab")
			(effects
				(font
					(size 1.27 1.27)
				)
			)
		)
		(duplicate_pad_numbers_are_jumpers no)
		(fp_line
			(start 0.7874 0.4064)
			(end -0.7874 0.4064)
			(stroke
				(width 0.1524)
				(type default)
			)
			(layer "F.SilkS")
		)
		(fp_line
			(start 0.7874 -0.4064)
			(end 0.7874 0.4064)
			(stroke
				(width 0.1524)
				(type default)
			)
			(layer "F.SilkS")
		)
		(fp_line
			(start -0.7874 0.4064)
			(end -0.7874 -0.4064)
			(stroke
				(width 0.1524)
				(type default)
			)
			(layer "F.SilkS")
		)
		(fp_line
			(start -0.7874 -0.4064)
			(end 0.7874 -0.4064)
			(stroke
				(width 0.1524)
				(type default)
			)
			(layer "F.SilkS")
		)
		(fp_line
			(start 0.67945 0.3048)
			(end 0.120396 0.3048)
			(stroke
				(width 0.1)
				(type default)
			)
			(layer "F.Fab")
		)
		(fp_line
			(start 0.67945 -0.3048)
			(end 0.67945 0.3048)
			(stroke
				(width 0.1)
				(type default)
			)
			(layer "F.Fab")
		)
		(fp_line
			(start 0.12065 -0.2794)
			(end 0.12065 -0.3048)
			(stroke
				(width 0.1)
				(type default)
			)
			(layer "F.Fab")
		)
		(fp_line
			(start 0.12065 -0.3048)
			(end 0.67945 -0.3048)
			(stroke
				(width 0.1)
				(type default)
			)
			(layer "F.Fab")
		)
		(fp_line
			(start 0.120396 0.3048)
			(end 0.120396 0.2794)
			(stroke
				(width 0.1)
				(type default)
			)
			(layer "F.Fab")
		)
		(fp_line
			(start 0.120396 0.2794)
			(end -0.12065 0.2794)
			(stroke
				(width 0.1)
				(type default)
			)
			(layer "F.Fab")
		)
		(fp_line
			(start -0.12065 0.3048)
			(end -0.67945 0.3048)
			(stroke
				(width 0.1)
				(type default)
			)
			(layer "F.Fab")
		)
		(fp_line
			(start -0.12065 0.2794)
			(end -0.12065 0.3048)
			(stroke
				(width 0.1)
				(type default)
			)
			(layer "F.Fab")
		)
		(fp_line
			(start -0.12065 -0.2794)
			(end 0.12065 -0.2794)
			(stroke
				(width 0.1)
				(type default)
			)
			(layer "F.Fab")
		)
		(fp_line
			(start -0.12065 -0.305054)
			(end -0.12065 -0.2794)
			(stroke
				(width 0.1)
				(type default)
			)
			(layer "F.Fab")
		)
		(fp_line
			(start -0.67945 0.3048)
			(end -0.67945 -0.305054)
			(stroke
				(width 0.1)
				(type default)
			)
			(layer "F.Fab")
		)
		(fp_line
			(start -0.67945 -0.305054)
			(end -0.12065 -0.305054)
			(stroke
				(width 0.1)
				(type default)
			)
			(layer "F.Fab")
		)
		(pad "1" smd circle
			(at -0.40005 0 180)
			(size 0 0)
			(layers "F.Cu" "F.Mask" "F.Paste")
			(net "FM_9ZXL045_P1_1_OE_N")
		)
		(pad "2" smd circle
			(at 0.40005 0 180)
			(size 0 0)
			(layers "F.Cu" "F.Mask" "F.Paste")
			(net "GND")
		)
	)
	(footprint ""
		(layer "F.Cu")
		(at 318.300608 -25.27935 90)
		(property "Reference" "C553"
			(at 0 0 90)
			(layer "F.SilkS")
			(hide yes)
			(effects
				(font
					(size 1.27 1.27)
				)
			)
		)
		(property "Value" ""
			(at 0 0 90)
			(layer "F.Fab")
			(effects
				(font
					(size 1.27 1.27)
				)
			)
		)
		(duplicate_pad_numbers_are_jumpers no)
		(fp_line
			(start 0.7874 -0.4064)
			(end 0.7874 0.4064)
			(stroke
				(width 0.1524)
				(type default)
			)
			(layer "F.SilkS")
		)
		(fp_line
			(start -0.7874 -0.4064)
			(end 0.7874 -0.4064)
			(stroke
				(width 0.1524)
				(type default)
			)
			(layer "F.SilkS")
		)
		(fp_line
			(start 0.7874 0.4064)
			(end -0.7874 0.4064)
			(stroke
				(width 0.1524)
				(type default)
			)
			(layer "F.SilkS")
		)
		(fp_line
			(start -0.7874 0.4064)
			(end -0.7874 -0.4064)
			(stroke
				(width 0.1524)
				(type default)
			)
			(layer "F.SilkS")
		)
		(fp_line
			(start -0.12065 -0.305054)
			(end -0.12065 -0.2794)
			(stroke
				(width 0.1)
				(type default)
			)
			(layer "F.Fab")
		)
		(fp_line
			(start -0.67945 -0.305054)
			(end -0.12065 -0.305054)
			(stroke
				(width 0.1)
				(type default)
			)
			(layer "F.Fab")
		)
		(fp_line
			(start 0.67945 -0.3048)
			(end 0.67945 0.3048)
			(stroke
				(width 0.1)
				(type default)
			)
			(layer "F.Fab")
		)
		(fp_line
			(start 0.12065 -0.3048)
			(end 0.67945 -0.3048)
			(stroke
				(width 0.1)
				(type default)
			)
			(layer "F.Fab")
		)
		(fp_line
			(start 0.12065 -0.2794)
			(end 0.12065 -0.3048)
			(stroke
				(width 0.1)
				(type default)
			)
			(layer "F.Fab")
		)
		(fp_line
			(start -0.12065 -0.2794)
			(end 0.12065 -0.2794)
			(stroke
				(width 0.1)
				(type default)
			)
			(layer "F.Fab")
		)
		(fp_line
			(start 0.120396 0.2794)
			(end -0.12065 0.2794)
			(stroke
				(width 0.1)
				(type default)
			)
			(layer "F.Fab")
		)
		(fp_line
			(start -0.12065 0.2794)
			(end -0.12065 0.3048)
			(stroke
				(width 0.1)
				(type default)
			)
			(layer "F.Fab")
		)
		(fp_line
			(start 0.67945 0.3048)
			(end 0.120396 0.3048)
			(stroke
				(width 0.1)
				(type default)
			)
			(layer "F.Fab")
		)
		(fp_line
			(start 0.120396 0.3048)
			(end 0.120396 0.2794)
			(stroke
				(width 0.1)
				(type default)
			)
			(layer "F.Fab")
		)
		(fp_line
			(start -0.12065 0.3048)
			(end -0.67945 0.3048)
			(stroke
				(width 0.1)
				(type default)
			)
			(layer "F.Fab")
		)
		(fp_line
			(start -0.67945 0.3048)
			(end -0.67945 -0.305054)
			(stroke
				(width 0.1)
				(type default)
			)
			(layer "F.Fab")
		)
		(pad "1" smd circle
			(at -0.40005 0 90)
			(size 0 0)
			(layers "F.Cu" "F.Mask" "F.Paste")
			(net "P3V3_AUX")
		)
		(pad "2" smd circle
			(at 0.40005 0 90)
			(size 0 0)
			(layers "F.Cu" "F.Mask" "F.Paste")
			(net "GND")
		)
	)
)
